# TIMECARD (Time Appliance Project (Time Card)) — schematic netlist excerpt (pin names and nets, part order shuffled) for the footprints in the layout excerpt that follows; sources: Cadence DE-HDL packaged netlist, KiCad conversion of R4006-B0001-02_R01.brd

R158  RESISTOR  4.7KOHM 1%  pkg SMC_0402R_H016  page 16 : \1\ = XP3R3V_FPGA ; \2\ = UNNAMED_5_24LC16BTISTTSSOP8_I15
R107  RESISTOR  4.7KOHM 1%  pkg SMC_0402R_H016  page 21 : \1\ = XP3R3V_FPGA ; \2\ = FPGA_IN_MAC_USB_OC_N

(kicad_pcb
	(version 20260206)
	(generator "pcbnew")
	(generator_version "10.0")
	(general
		(thickness 1.6)
		(legacy_teardrops no)
	)
	(paper "A4")
	(title_block
		(title "timecard-production-celestica-r4006 — R4006-B0001-02_R01.brd")
		(comment 1 "Time Appliance Project (Time Card) / footprints 1047-1048 of 1113")
	)
	(layers
		(0 "F.Cu" signal "TOP")
		(4 "In1.Cu" signal "L02_GND1")
		(6 "In2.Cu" signal "L03_SIG1")
		(8 "In3.Cu" signal "L04_GND2")
		(10 "In4.Cu" signal "L05_VCC1")
		(12 "In5.Cu" signal "L06_VCC2")
		(14 "In6.Cu" signal "L07_GND3")
		(16 "In7.Cu" signal "L08_SIG2")
		(18 "In8.Cu" signal "L09_GND4")
		(2 "B.Cu" signal "BOTTOM")
		(9 "F.Adhes" user "F.Adhesive")
		(11 "B.Adhes" user "B.Adhesive")
		(13 "F.Paste" user "Package Geometry/Pastemask Top")
		(15 "B.Paste" user "Package Geometry/Pastemask Bottom")
		(5 "F.SilkS" user "Ref Des/Silkscreen Top")
		(7 "B.SilkS" user "Ref Des/Silkscreen Bottom")
		(1 "F.Mask" user "Board Geometry/Soldermask Top")
		(3 "B.Mask" user "Board Geometry/Soldermask Bottom")
		(17 "Dwgs.User" user "User.Drawings")
		(19 "Cmts.User" user "User.Comments")
		(21 "Eco1.User" user "User.Eco1")
		(23 "Eco2.User" user "User.Eco2")
		(25 "Edge.Cuts" user "Board Geometry/Outline")
		(27 "Margin" user)
		(31 "F.CrtYd" user "Package Geometry/Place Bound Top")
		(29 "B.CrtYd" user "Package Geometry/Place Bound Bottom")
		(35 "F.Fab" user "Ref Des/Assembly Top")
		(33 "B.Fab" user "Ref Des/Assembly Bottom")
	)
	(footprint ""
		(layer "B.Cu")
		(at 33.782 -19.1262 180)
		(property "Reference" "R158"
			(at -3.175 -0.62357 0)
			(unlocked yes)
			(layer "B.SilkS")
			(effects
				(font
					(size 0.7874 0.5842)
					(thickness 0.1524)
				)
				(justify mirror)
			)
		)
		(property "Value" "VAL*"
			(at -0.02032 2.13233 180)
			(unlocked yes)
			(layer "B.Fab")
			(hide yes)
			(effects
				(font
					(size 0.7874 0.5842)
					(thickness 0.1524)
				)
				(justify mirror)
			)
		)
		(property "Device Type" "RESISTOR-G155-14701-01,4.7KOHMA"
			(at -0.008382 1.210564 180)
			(unlocked yes)
			(layer "B.Fab")
			(hide yes)
			(effects
				(font
					(size 0.7874 0.5842)
					(thickness 0.1524)
				)
				(justify mirror)
			)
		)
		(property "User Part Number" "PARTNUM*"
			(at -0.02032 4.024884 180)
			(unlocked yes)
			(layer "Cmts.User")
			(hide yes)
			(effects
				(font
					(size 0.7874 0.5842)
					(thickness 0.1524)
				)
				(justify mirror)
			)
		)
		(property "Tolerance" "TOL*"
			(at -0.044704 3.05435 180)
			(unlocked yes)
			(layer "Cmts.User")
			(hide yes)
			(effects
				(font
					(size 0.7874 0.5842)
					(thickness 0.1524)
				)
				(justify mirror)
			)
		)
		(duplicate_pad_numbers_are_jumpers no)
		(fp_line
			(start 1.143 0.5588)
			(end -1.143 0.5588)
			(stroke
				(width 0.1)
				(type default)
			)
			(layer "B.SilkS")
		)
		(fp_line
			(start 1.143 -0.5588)
			(end 1.143 0.5588)
			(stroke
				(width 0.1)
				(type default)
			)
			(layer "B.SilkS")
		)
		(fp_line
			(start -1.143 0.5588)
			(end -1.143 -0.5588)
			(stroke
				(width 0.1)
				(type default)
			)
			(layer "B.SilkS")
		)
		(fp_line
			(start -1.143 -0.5588)
			(end 1.143 -0.5588)
			(stroke
				(width 0.1)
				(type default)
			)
			(layer "B.SilkS")
		)
		(fp_rect
			(start 1.143 -0.5588)
			(end -1.143 0.5588)
			(stroke
				(width 0)
				(type default)
			)
			(fill no)
			(layer "B.CrtYd")
		)
		(fp_line
			(start 0.508 0.3048)
			(end -0.508 0.3048)
			(stroke
				(width 0.1)
				(type default)
			)
			(layer "B.Fab")
		)
		(fp_line
			(start 0.508 -0.3048)
			(end 0.508 0.3048)
			(stroke
				(width 0.1)
				(type default)
			)
			(layer "B.Fab")
		)
		(fp_line
			(start -0.508 0.3048)
			(end -0.508 -0.3048)
			(stroke
				(width 0.1)
				(type default)
			)
			(layer "B.Fab")
		)
		(fp_line
			(start -0.508 -0.3048)
			(end 0.508 -0.3048)
			(stroke
				(width 0.1)
				(type default)
			)
			(layer "B.Fab")
		)
		(pad "1" smd rect
			(at 0.5334 0)
			(size 0.7112 0.6096)
			(layers "B.Cu" "B.Mask" "B.Paste")
			(net "XP3R3V_FPGA")
		)
		(pad "2" smd rect
			(at -0.5334 0)
			(size 0.7112 0.6096)
			(layers "B.Cu" "B.Mask" "B.Paste")
			(net "UNNAMED_5_24LC16BTISTTSSOP8_I15")
		)
		(zone
			(layer "B.Cu")
			(hatch none 0.5)
			(connect_pads
				(clearance 0)
			)
			(min_thickness 0.25)
			(keepout
				(tracks allowed)
				(vias not_allowed)
				(pads allowed)
				(copperpour not_allowed)
				(footprints allowed)
			)
			(placement
				(enabled no)
				(sheetname "")
			)
			(fill
				(thermal_gap 0.5)
				(thermal_bridge_width 0.5)
				(island_removal_mode 0)
			)
			(polygon
				(pts
					(xy 33.7058 -18.8214) (xy 33.8582 -18.8214) (xy 33.8582 -19.431) (xy 33.7058 -19.431)
				)
			)
		)
	)
	(footprint ""
		(layer "B.Cu")
		(at 64.262 -60.325 180)
		(property "Reference" "R107"
			(at 2.159 1.10363 0)
			(unlocked yes)
			(layer "B.SilkS")
			(effects
				(font
					(size 0.7874 0.5842)
					(thickness 0.1524)
				)
				(justify mirror)
			)
		)
		(property "Value" "VAL*"
			(at -0.02032 2.13233 180)
			(unlocked yes)
			(layer "B.Fab")
			(hide yes)
			(effects
				(font
					(size 0.7874 0.5842)
					(thickness 0.1524)
				)
				(justify mirror)
			)
		)
		(property "Tolerance" "TOL*"
			(at -0.044704 3.05435 180)
			(unlocked yes)
			(layer "Cmts.User")
			(hide yes)
			(effects
				(font
					(size 0.7874 0.5842)
					(thickness 0.1524)
				)
				(justify mirror)
			)
		)
		(property "User Part Number" "PARTNUM*"
			(at -0.02032 4.024884 180)
			(unlocked yes)
			(layer "Cmts.User")
			(hide yes)
			(effects
				(font
					(size 0.7874 0.5842)
					(thickness 0.1524)
				)
				(justify mirror)
			)
		)
		(property "Device Type" "RESISTOR-G155-14701-01,4.7KOHMA"
			(at -0.008382 1.210564 180)
			(unlocked yes)
			(layer "B.Fab")
			(hide yes)
			(effects
				(font
					(size 0.7874 0.5842)
					(thickness 0.1524)
				)
				(justify mirror)
			)
		)
		(duplicate_pad_numbers_are_jumpers no)
		(fp_line
			(start 1.143 0.5588)
			(end -1.143 0.5588)
			(stroke
				(width 0.1)
				(type default)
			)
			(layer "B.SilkS")
		)
		(fp_line
			(start 1.143 -0.5588)
			(end 1.143 0.5588)
			(stroke
				(width 0.1)
				(type default)
			)
			(layer "B.SilkS")
		)
		(fp_line
			(start -1.143 0.5588)
			(end -1.143 -0.5588)
			(stroke
				(width 0.1)
				(type default)
			)
			(layer "B.SilkS")
		)
		(fp_line
			(start -1.143 -0.5588)
			(end 1.143 -0.5588)
			(stroke
				(width 0.1)
				(type default)
			)
			(layer "B.SilkS")
		)
		(fp_rect
			(start -1.143 -0.5588)
			(end 1.143 0.5588)
			(stroke
				(width 0)
				(type default)
			)
			(fill no)
			(layer "B.CrtYd")
		)
		(fp_line
			(start 0.508 0.3048)
			(end -0.508 0.3048)
			(stroke
				(width 0.1)
				(type default)
			)
			(layer "B.Fab")
		)
		(fp_line
			(start 0.508 -0.3048)
			(end 0.508 0.3048)
			(stroke
				(width 0.1)
				(type default)
			)
			(layer "B.Fab")
		)
		(fp_line
			(start -0.508 0.3048)
			(end -0.508 -0.3048)
			(stroke
				(width 0.1)
				(type default)
			)
			(layer "B.Fab")
		)
		(fp_line
			(start -0.508 -0.3048)
			(end 0.508 -0.3048)
			(stroke
				(width 0.1)
				(type default)
			)
			(layer "B.Fab")
		)
		(pad "1" smd rect
			(at 0.5334 0)
			(size 0.7112 0.6096)
			(layers "B.Cu" "B.Mask" "B.Paste")
			(net "XP3R3V_FPGA")
		)
		(pad "2" smd rect
			(at -0.5334 0)
			(size 0.7112 0.6096)
			(layers "B.Cu" "B.Mask" "B.Paste")
			(net "FPGA_IN_MAC_USB_OC_N")
		)
		(zone
			(layer "B.Cu")
			(hatch none 0.5)
			(connect_pads
				(clearance 0)
			)
			(min_thickness 0.25)
			(keepout
				(tracks allowed)
				(vias not_allowed)
				(pads allowed)
				(copperpour not_allowed)
				(footprints allowed)
			)
			(placement
				(enabled no)
				(sheetname "")
			)
			(fill
				(thermal_gap 0.5)
				(thermal_bridge_width 0.5)
				(island_removal_mode 0)
			)
			(polygon
				(pts
					(xy 64.3382 -60.0202) (xy 64.3382 -60.6298) (xy 64.1858 -60.6298) (xy 64.1858 -60.0202)
				)
			)
		)
	)
)
